(kicad_pcb
	(version 20260206)
	(generator "pcbnew")
	(generator_version "10.0")
	(general
		(thickness 1.6)
		(legacy_teardrops no)
	)
	(paper "A4")
	(title_block
		(title "Wiwynn_Tioga_Pass_MB.brd")
		(comment 1 "Tioga Pass / footprints 1128-1134 of 4770")
	)
	(layers
		(0 "F.Cu" signal "TOP")
		(4 "In1.Cu" signal "L2GND")
		(6 "In2.Cu" signal "L3")
		(8 "In3.Cu" signal "L4GND")
		(10 "In4.Cu" signal "L5")
		(12 "In5.Cu" signal "L6GND")
		(14 "In6.Cu" signal "L7VCC")
		(16 "In7.Cu" signal "L8VCC")
		(18 "In8.Cu" signal "L9GND")
		(20 "In9.Cu" signal "L10")
		(22 "In10.Cu" signal "L11GND")
		(24 "In11.Cu" signal "L12")
		(26 "In12.Cu" signal "L13GND")
		(2 "B.Cu" signal "BOTTOM")
		(9 "F.Adhes" user "F.Adhesive")
		(11 "B.Adhes" user "B.Adhesive")
		(13 "F.Paste" user "Package Geometry/Pastemask Top")
		(15 "B.Paste" user "Package Geometry/Pastemask Bottom")
		(5 "F.SilkS" user "Ref Des/Silkscreen Top")
		(7 "B.SilkS" user "Ref Des/Silkscreen Bottom")
		(1 "F.Mask" user "Board Geometry/Soldermask Top")
		(3 "B.Mask" user "Board Geometry/Soldermask Bottom")
		(17 "Dwgs.User" user "User.Drawings")
		(19 "Cmts.User" user "User.Comments")
		(21 "Eco1.User" user "User.Eco1")
		(23 "Eco2.User" user "User.Eco2")
		(25 "Edge.Cuts" user "Board Geometry/Outline")
		(27 "Margin" user)
		(31 "F.CrtYd" user "Package Geometry/Place Bound Top")
		(29 "B.CrtYd" user "Package Geometry/Place Bound Bottom")
		(35 "F.Fab" user "Ref Des/Assembly Top")
		(33 "B.Fab" user "Ref Des/Assembly Bottom")
	)
	(footprint ""
		(layer "F.Cu")
		(at 169.037 -73.7108 90)
		(property "Reference" "C4D27"
			(at 0 0 90)
			(layer "F.SilkS")
			(hide yes)
			(effects
				(font
					(size 1.27 1.27)
				)
			)
		)
		(property "Value" ""
			(at 0 0 90)
			(layer "F.Fab")
			(effects
				(font
					(size 1.27 1.27)
				)
			)
		)
		(duplicate_pad_numbers_are_jumpers no)
		(fp_poly
			(pts
				(xy 0.3048 -0.1016) (xy 0.3048 0.9906) (xy -0.3048 0.9906) (xy -0.3048 -0.1016)
			)
			(stroke
				(width 0)
				(type default)
			)
			(fill no)
			(layer "F.CrtYd")
		)
		(fp_line
			(start 0.3048 -0.1016)
			(end -0.3048 -0.1016)
			(stroke
				(width 0.1)
				(type default)
			)
			(layer "F.Fab")
		)
		(fp_line
			(start -0.3048 -0.1016)
			(end -0.3048 0.9906)
			(stroke
				(width 0.1)
				(type default)
			)
			(layer "F.Fab")
		)
		(fp_line
			(start 0.3048 0.9906)
			(end 0.3048 -0.1016)
			(stroke
				(width 0.1)
				(type default)
			)
			(layer "F.Fab")
		)
		(fp_line
			(start -0.3048 0.9906)
			(end 0.3048 0.9906)
			(stroke
				(width 0.1)
				(type default)
			)
			(layer "F.Fab")
		)
		(pad "1" smd rect
			(at 0 0 90)
			(size 0.508 0.508)
			(layers "F.Cu" "F.Mask" "F.Paste")
			(net "P3V3_DB1200_R")
		)
		(pad "2" smd rect
			(at 0 0.889 90)
			(size 0.508 0.508)
			(layers "F.Cu" "F.Mask" "F.Paste")
			(net "GND")
		)
		(zone
			(layer "F.Cu")
			(hatch none 0.5)
			(connect_pads
				(clearance 0)
			)
			(min_thickness 0.25)
			(keepout
				(tracks allowed)
				(vias not_allowed)
				(pads allowed)
				(copperpour not_allowed)
				(footprints allowed)
			)
			(placement
				(enabled no)
				(sheetname "")
			)
			(fill
				(thermal_gap 0.5)
				(thermal_bridge_width 0.5)
				(island_removal_mode 0)
			)
			(polygon
				(pts
					(xy 169.291 -73.4568) (xy 169.291 -73.9648) (xy 169.672 -73.9648) (xy 169.672 -73.4568)
				)
			)
		)
		(zone
			(layer "F.Cu")
			(hatch none 0.5)
			(connect_pads
				(clearance 0)
			)
			(min_thickness 0.25)
			(keepout
				(tracks not_allowed)
				(vias allowed)
				(pads allowed)
				(copperpour not_allowed)
				(footprints allowed)
			)
			(placement
				(enabled no)
				(sheetname "")
			)
			(fill
				(thermal_gap 0.5)
				(thermal_bridge_width 0.5)
				(island_removal_mode 0)
			)
			(polygon
				(pts
					(xy 169.672 -73.4568) (xy 169.672 -73.9648) (xy 169.291 -73.9648) (xy 169.291 -73.4568)
				)
			)
		)
	)
	(footprint ""
		(layer "F.Cu")
		(at 258.064 -140.1318 -90)
		(property "Reference" "C5A15"
			(at 1.848866 0.752348 270)
			(unlocked yes)
			(layer "F.SilkS")
			(effects
				(font
					(size 1.27 0.9652)
					(thickness 0.1524)
				)
			)
		)
		(property "Value" ""
			(at 0 0 270)
			(layer "F.Fab")
			(effects
				(font
					(size 1.27 1.27)
				)
			)
		)
		(duplicate_pad_numbers_are_jumpers no)
		(fp_rect
			(start -0.500126 1.598422)
			(end 0.500126 -0.201422)
			(stroke
				(width 0)
				(type default)
			)
			(fill no)
			(layer "F.CrtYd")
		)
		(fp_line
			(start -0.500126 1.598422)
			(end -0.500126 -0.201422)
			(stroke
				(width 0.1)
				(type default)
			)
			(layer "F.Fab")
		)
		(fp_line
			(start 0.500126 1.598422)
			(end -0.500126 1.598422)
			(stroke
				(width 0.1)
				(type default)
			)
			(layer "F.Fab")
		)
		(fp_line
			(start -0.500126 -0.201422)
			(end 0.500126 -0.201422)
			(stroke
				(width 0.1)
				(type default)
			)
			(layer "F.Fab")
		)
		(fp_line
			(start 0.500126 -0.201422)
			(end 0.500126 1.598422)
			(stroke
				(width 0.1)
				(type default)
			)
			(layer "F.Fab")
		)
		(pad "1" smd rect
			(at 0 0 180)
			(size 0.889 0.9906)
			(layers "F.Cu" "F.Mask" "F.Paste")
			(net "PVDDQ_DEF")
		)
		(pad "2" smd rect
			(at 0 1.397 180)
			(size 0.889 0.9906)
			(layers "F.Cu" "F.Mask" "F.Paste")
			(net "GND")
		)
		(zone
			(layer "F.Cu")
			(hatch none 0.5)
			(connect_pads
				(clearance 0)
			)
			(min_thickness 0.25)
			(keepout
				(tracks not_allowed)
				(vias allowed)
				(pads allowed)
				(copperpour not_allowed)
				(footprints allowed)
			)
			(placement
				(enabled no)
				(sheetname "")
			)
			(fill
				(thermal_gap 0.5)
				(thermal_bridge_width 0.5)
				(island_removal_mode 0)
			)
			(polygon
				(pts
					(xy 257.1115 -140.6271) (xy 257.1115 -139.6365) (xy 257.6195 -139.6365) (xy 257.6195 -140.6271)
				)
			)
		)
		(zone
			(layer "F.Cu")
			(hatch none 0.5)
			(connect_pads
				(clearance 0)
			)
			(min_thickness 0.25)
			(keepout
				(tracks allowed)
				(vias not_allowed)
				(pads allowed)
				(copperpour not_allowed)
				(footprints allowed)
			)
			(placement
				(enabled no)
				(sheetname "")
			)
			(fill
				(thermal_gap 0.5)
				(thermal_bridge_width 0.5)
				(island_removal_mode 0)
			)
			(polygon
				(pts
					(xy 257.1115 -140.6271) (xy 257.1115 -139.6365) (xy 257.6195 -139.6365) (xy 257.6195 -140.6271)
				)
			)
		)
	)
	(footprint ""
		(layer "F.Cu")
		(at 321.16522 -119.26316 -90)
		(property "Reference" "C841"
			(at -0.8382 -0.67818 270)
			(unlocked yes)
			(layer "F.SilkS")
			(effects
				(font
					(size 0.4064 0.254)
					(thickness 0.1524)
				)
				(justify left)
			)
		)
		(property "Value" ""
			(at 0 0 270)
			(layer "F.Fab")
			(effects
				(font
					(size 1.27 1.27)
				)
			)
		)
		(duplicate_pad_numbers_are_jumpers no)
		(fp_poly
			(pts
				(xy 0.3048 -0.1016) (xy 0.3048 0.9906) (xy -0.3048 0.9906) (xy -0.3048 -0.1016)
			)
			(stroke
				(width 0)
				(type default)
			)
			(fill no)
			(layer "F.CrtYd")
		)
		(fp_line
			(start -0.3048 0.9906)
			(end 0.3048 0.9906)
			(stroke
				(width 0.1)
				(type default)
			)
			(layer "F.Fab")
		)
		(fp_line
			(start 0.3048 0.9906)
			(end 0.3048 -0.1016)
			(stroke
				(width 0.1)
				(type default)
			)
			(layer "F.Fab")
		)
		(fp_line
			(start -0.3048 -0.1016)
			(end -0.3048 0.9906)
			(stroke
				(width 0.1)
				(type default)
			)
			(layer "F.Fab")
		)
		(fp_line
			(start 0.3048 -0.1016)
			(end -0.3048 -0.1016)
			(stroke
				(width 0.1)
				(type default)
			)
			(layer "F.Fab")
		)
		(pad "1" smd rect
			(at 0 0 270)
			(size 0.508 0.508)
			(layers "F.Cu" "F.Mask" "F.Paste")
			(net "P3E_CPU0_PE1_PCH_TXP<12>")
		)
		(pad "2" smd rect
			(at 0 0.889 270)
			(size 0.508 0.508)
			(layers "F.Cu" "F.Mask" "F.Paste")
			(net "P3E_CPU0_PE1_PCH_CON_TXP<12>")
		)
		(zone
			(layer "F.Cu")
			(hatch none 0.5)
			(connect_pads
				(clearance 0)
			)
			(min_thickness 0.25)
			(keepout
				(tracks not_allowed)
				(vias allowed)
				(pads allowed)
				(copperpour not_allowed)
				(footprints allowed)
			)
			(placement
				(enabled no)
				(sheetname "")
			)
			(fill
				(thermal_gap 0.5)
				(thermal_bridge_width 0.5)
				(island_removal_mode 0)
			)
			(polygon
				(pts
					(xy 320.53022 -119.51716) (xy 320.53022 -119.00916) (xy 320.91122 -119.00916) (xy 320.91122 -119.51716)
				)
			)
		)
		(zone
			(layer "F.Cu")
			(hatch none 0.5)
			(connect_pads
				(clearance 0)
			)
			(min_thickness 0.25)
			(keepout
				(tracks allowed)
				(vias not_allowed)
				(pads allowed)
				(copperpour not_allowed)
				(footprints allowed)
			)
			(placement
				(enabled no)
				(sheetname "")
			)
			(fill
				(thermal_gap 0.5)
				(thermal_bridge_width 0.5)
				(island_removal_mode 0)
			)
			(polygon
				(pts
					(xy 320.91122 -119.51716) (xy 320.91122 -119.00916) (xy 320.53022 -119.00916) (xy 320.53022 -119.51716)
				)
			)
		)
	)
	(footprint ""
		(layer "F.Cu")
		(at 374.278144 -10.916158)
		(property "Reference" "C7G15"
			(at 0 0 0)
			(layer "F.SilkS")
			(hide yes)
			(effects
				(font
					(size 1.27 1.27)
				)
			)
		)
		(property "Value" ""
			(at 0 0 0)
			(layer "F.Fab")
			(effects
				(font
					(size 1.27 1.27)
				)
			)
		)
		(duplicate_pad_numbers_are_jumpers no)
		(fp_rect
			(start -0.3048 0.9906)
			(end 0.3048 -0.1016)
			(stroke
				(width 0)
				(type default)
			)
			(fill no)
			(layer "F.CrtYd")
		)
		(fp_line
			(start -0.3048 -0.1016)
			(end -0.3048 0.9906)
			(stroke
				(width 0.1)
				(type default)
			)
			(layer "F.Fab")
		)
		(fp_line
			(start -0.3048 0.9906)
			(end 0.3048 0.9906)
			(stroke
				(width 0.1)
				(type default)
			)
			(layer "F.Fab")
		)
		(fp_line
			(start 0.3048 -0.1016)
			(end -0.3048 -0.1016)
			(stroke
				(width 0.1)
				(type default)
			)
			(layer "F.Fab")
		)
		(fp_line
			(start 0.3048 0.9906)
			(end 0.3048 -0.1016)
			(stroke
				(width 0.1)
				(type default)
			)
			(layer "F.Fab")
		)
		(pad "1" smd rect
			(at 0 0)
			(size 0.508 0.508)
			(layers "F.Cu" "F.Mask" "F.Paste")
			(net "P3E_CPU0_PE2_SS_TXP<10>")
		)
		(pad "2" smd rect
			(at 0 0.889)
			(size 0.508 0.508)
			(layers "F.Cu" "F.Mask" "F.Paste")
			(net "P3E_CPU0_PE2_SS_C_TXP<10>")
		)
		(zone
			(layer "F.Cu")
			(hatch none 0.5)
			(connect_pads
				(clearance 0)
			)
			(min_thickness 0.25)
			(keepout
				(tracks allowed)
				(vias not_allowed)
				(pads allowed)
				(copperpour not_allowed)
				(footprints allowed)
			)
			(placement
				(enabled no)
				(sheetname "")
			)
			(fill
				(thermal_gap 0.5)
				(thermal_bridge_width 0.5)
				(island_removal_mode 0)
			)
			(polygon
				(pts
					(xy 374.024144 -10.281158) (xy 374.532144 -10.281158) (xy 374.532144 -10.662158) (xy 374.024144 -10.662158)
				)
			)
		)
		(zone
			(layer "F.Cu")
			(hatch none 0.5)
			(connect_pads
				(clearance 0)
			)
			(min_thickness 0.25)
			(keepout
				(tracks not_allowed)
				(vias allowed)
				(pads allowed)
				(copperpour not_allowed)
				(footprints allowed)
			)
			(placement
				(enabled no)
				(sheetname "")
			)
			(fill
				(thermal_gap 0.5)
				(thermal_bridge_width 0.5)
				(island_removal_mode 0)
			)
			(polygon
				(pts
					(xy 374.024144 -10.281158) (xy 374.532144 -10.281158) (xy 374.532144 -10.662158) (xy 374.024144 -10.662158)
				)
			)
		)
	)
	(footprint ""
		(layer "F.Cu")
		(at 29.965904 -94.604332)
		(property "Reference" "CT57"
			(at -3.37693 1.9304 90)
			(unlocked yes)
			(layer "F.SilkS")
			(effects
				(font
					(size 0.7874 0.5842)
					(thickness 0.1524)
				)
				(justify left)
			)
		)
		(property "Value" ""
			(at 0 0 0)
			(layer "F.Fab")
			(effects
				(font
					(size 1.27 1.27)
				)
			)
		)
		(duplicate_pad_numbers_are_jumpers no)
		(fp_poly
			(pts
				(xy 0.3048 -0.1016) (xy 0.3048 0.9906) (xy -0.3048 0.9906) (xy -0.3048 -0.1016)
			)
			(stroke
				(width 0)
				(type default)
			)
			(fill no)
			(layer "F.CrtYd")
		)
		(fp_line
			(start -0.3048 -0.1016)
			(end -0.3048 0.9906)
			(stroke
				(width 0.1)
				(type default)
			)
			(layer "F.Fab")
		)
		(fp_line
			(start -0.3048 0.9906)
			(end 0.3048 0.9906)
			(stroke
				(width 0.1)
				(type default)
			)
			(layer "F.Fab")
		)
		(fp_line
			(start 0.3048 -0.1016)
			(end -0.3048 -0.1016)
			(stroke
				(width 0.1)
				(type default)
			)
			(layer "F.Fab")
		)
		(fp_line
			(start 0.3048 0.9906)
			(end 0.3048 -0.1016)
			(stroke
				(width 0.1)
				(type default)
			)
			(layer "F.Fab")
		)
		(pad "1" smd rect
			(at 0 0)
			(size 0.508 0.508)
			(layers "F.Cu" "F.Mask" "F.Paste")
			(net "VR_PVSA_CPU1_BIREF1")
		)
		(pad "2" smd rect
			(at 0 0.889)
			(size 0.508 0.508)
			(layers "F.Cu" "F.Mask" "F.Paste")
			(net "GND")
		)
		(zone
			(layer "F.Cu")
			(hatch none 0.5)
			(connect_pads
				(clearance 0)
			)
			(min_thickness 0.25)
			(keepout
				(tracks allowed)
				(vias not_allowed)
				(pads allowed)
				(copperpour not_allowed)
				(footprints allowed)
			)
			(placement
				(enabled no)
				(sheetname "")
			)
			(fill
				(thermal_gap 0.5)
				(thermal_bridge_width 0.5)
				(island_removal_mode 0)
			)
			(polygon
				(pts
					(xy 29.711904 -94.350332) (xy 30.219904 -94.350332) (xy 30.219904 -93.969332) (xy 29.711904 -93.969332)
				)
			)
		)
		(zone
			(layer "F.Cu")
			(hatch none 0.5)
			(connect_pads
				(clearance 0)
			)
			(min_thickness 0.25)
			(keepout
				(tracks not_allowed)
				(vias allowed)
				(pads allowed)
				(copperpour not_allowed)
				(footprints allowed)
			)
			(placement
				(enabled no)
				(sheetname "")
			)
			(fill
				(thermal_gap 0.5)
				(thermal_bridge_width 0.5)
				(island_removal_mode 0)
			)
			(polygon
				(pts
					(xy 29.711904 -93.969332) (xy 30.219904 -93.969332) (xy 30.219904 -94.350332) (xy 29.711904 -94.350332)
				)
			)
		)
	)
	(footprint ""
		(layer "F.Cu")
		(at 181.356 -64.135 180)
		(property "Reference" "R4E5"
			(at 0 0 180)
			(layer "F.SilkS")
			(hide yes)
			(effects
				(font
					(size 1.27 1.27)
				)
			)
		)
		(property "Value" ""
			(at 0 0 180)
			(layer "F.Fab")
			(effects
				(font
					(size 1.27 1.27)
				)
			)
		)
		(duplicate_pad_numbers_are_jumpers no)
		(fp_rect
			(start 0.2794 -0.1016)
			(end -0.2794 0.9906)
			(stroke
				(width 0)
				(type default)
			)
			(fill no)
			(layer "F.CrtYd")
		)
		(fp_line
			(start 0.2794 0.9906)
			(end 0.2794 -0.1016)
			(stroke
				(width 0.1)
				(type default)
			)
			(layer "F.Fab")
		)
		(fp_line
			(start 0.2794 -0.1016)
			(end -0.2794 -0.1016)
			(stroke
				(width 0.1)
				(type default)
			)
			(layer "F.Fab")
		)
		(fp_line
			(start -0.2794 0.9906)
			(end 0.2794 0.9906)
			(stroke
				(width 0.1)
				(type default)
			)
			(layer "F.Fab")
		)
		(fp_line
			(start -0.2794 -0.1016)
			(end -0.2794 0.9906)
			(stroke
				(width 0.1)
				(type default)
			)
			(layer "F.Fab")
		)
		(pad "1" smd rect
			(at 0 0 180)
			(size 0.508 0.508)
			(layers "F.Cu" "F.Mask" "F.Paste")
			(net "P3V3_STBY")
		)
		(pad "2" smd rect
			(at 0 0.889 180)
			(size 0.508 0.508)
			(layers "F.Cu" "F.Mask" "F.Paste")
			(net "PWRGD_PVSA_CPU0_R")
		)
		(zone
			(layer "F.Cu")
			(hatch none 0.5)
			(connect_pads
				(clearance 0)
			)
			(min_thickness 0.25)
			(keepout
				(tracks not_allowed)
				(vias allowed)
				(pads allowed)
				(copperpour not_allowed)
				(footprints allowed)
			)
			(placement
				(enabled no)
				(sheetname "")
			)
			(fill
				(thermal_gap 0.5)
				(thermal_bridge_width 0.5)
				(island_removal_mode 0)
			)
			(polygon
				(pts
					(xy 181.102 -64.389) (xy 181.61 -64.389) (xy 181.61 -64.77) (xy 181.102 -64.77)
				)
			)
		)
		(zone
			(layer "F.Cu")
			(hatch none 0.5)
			(connect_pads
				(clearance 0)
			)
			(min_thickness 0.25)
			(keepout
				(tracks allowed)
				(vias not_allowed)
				(pads allowed)
				(copperpour not_allowed)
				(footprints allowed)
			)
			(placement
				(enabled no)
				(sheetname "")
			)
			(fill
				(thermal_gap 0.5)
				(thermal_bridge_width 0.5)
				(island_removal_mode 0)
			)
			(polygon
				(pts
					(xy 181.102 -64.389) (xy 181.61 -64.389) (xy 181.61 -64.77) (xy 181.102 -64.77)
				)
			)
		)
	)
	(footprint ""
		(layer "F.Cu")
		(at 112.2934 -83.8962)
		(property "Reference" "R3D4"
			(at 0 0 0)
			(layer "F.SilkS")
			(hide yes)
			(effects
				(font
					(size 1.27 1.27)
				)
			)
		)
		(property "Value" ""
			(at 0 0 0)
			(layer "F.Fab")
			(effects
				(font
					(size 1.27 1.27)
				)
			)
		)
		(duplicate_pad_numbers_are_jumpers no)
		(fp_poly
			(pts
				(xy -0.2794 -0.1016) (xy 0.2794 -0.1016) (xy 0.2794 0.9906) (xy -0.2794 0.9906)
			)
			(stroke
				(width 0)
				(type default)
			)
			(fill no)
			(layer "F.CrtYd")
		)
		(fp_line
			(start -0.2794 -0.1016)
			(end -0.2794 0.9906)
			(stroke
				(width 0.1)
				(type default)
			)
			(layer "F.Fab")
		)
		(fp_line
			(start -0.2794 0.9906)
			(end 0.2794 0.9906)
			(stroke
				(width 0.1)
				(type default)
			)
			(layer "F.Fab")
		)
		(fp_line
			(start 0.2794 -0.1016)
			(end -0.2794 -0.1016)
			(stroke
				(width 0.1)
				(type default)
			)
			(layer "F.Fab")
		)
		(fp_line
			(start 0.2794 0.9906)
			(end 0.2794 -0.1016)
			(stroke
				(width 0.1)
				(type default)
			)
			(layer "F.Fab")
		)
		(pad "1" smd rect
			(at 0 0)
			(size 0.508 0.508)
			(layers "F.Cu" "F.Mask" "F.Paste")
			(net "A_CPU1_MCP01_RBIAS")
		)
		(pad "2" smd rect
			(at 0 0.889)
			(size 0.508 0.508)
			(layers "F.Cu" "F.Mask" "F.Paste")
			(net "GND")
		)
		(zone
			(layer "F.Cu")
			(hatch none 0.5)
			(connect_pads
				(clearance 0)
			)
			(min_thickness 0.25)
			(keepout
				(tracks allowed)
				(vias not_allowed)
				(pads allowed)
				(copperpour not_allowed)
				(footprints allowed)
			)
			(placement
				(enabled no)
				(sheetname "")
			)
			(fill
				(thermal_gap 0.5)
				(thermal_bridge_width 0.5)
				(island_removal_mode 0)
			)
			(polygon
				(pts
					(xy 112.0394 -83.6422) (xy 112.5474 -83.6422) (xy 112.5474 -83.2612) (xy 112.0394 -83.2612)
				)
			)
		)
		(zone
			(layer "F.Cu")
			(hatch none 0.5)
			(connect_pads
				(clearance 0)
			)
			(min_thickness 0.25)
			(keepout
				(tracks not_allowed)
				(vias allowed)
				(pads allowed)
				(copperpour not_allowed)
				(footprints allowed)
			)
			(placement
				(enabled no)
				(sheetname "")
			)
			(fill
				(thermal_gap 0.5)
				(thermal_bridge_width 0.5)
				(island_removal_mode 0)
			)
			(polygon
				(pts
					(xy 112.0394 -83.2612) (xy 112.5474 -83.2612) (xy 112.5474 -83.6422) (xy 112.0394 -83.6422)
				)
			)
		)
	)
)
